(kicad_pcb
	(version 20260206)
	(generator "pcbnew")
	(generator_version "10.0")
	(general
		(thickness 1.6)
		(legacy_teardrops no)
	)
	(paper "A4")
	(title_block
		(title "01162023_DA0F0TEBIF0_F0T_Expander_BD_F_brd_V02_OCP.brd")
		(comment 1 "Grand Teton / footprints 5495-5501 of 9728")
	)
	(layers
		(0 "F.Cu" signal "TOP")
		(4 "In1.Cu" signal "GND")
		(6 "In2.Cu" signal "VCC")
		(8 "In3.Cu" signal "VCC1")
		(10 "In4.Cu" signal "GND1")
		(12 "In5.Cu" signal "IN1")
		(14 "In6.Cu" signal "GND2")
		(16 "In7.Cu" signal "IN2")
		(18 "In8.Cu" signal "GND3")
		(20 "In9.Cu" signal "IN3")
		(22 "In10.Cu" signal "GND4")
		(24 "In11.Cu" signal "IN4")
		(26 "In12.Cu" signal "GND5")
		(28 "In13.Cu" signal "IN5")
		(30 "In14.Cu" signal "GND6")
		(32 "In15.Cu" signal "IN6")
		(34 "In16.Cu" signal "GND7")
		(2 "B.Cu" signal "BOTTOM")
		(9 "F.Adhes" user "F.Adhesive")
		(11 "B.Adhes" user "B.Adhesive")
		(13 "F.Paste" user "Package Geometry/Pastemask Top")
		(15 "B.Paste" user "Package Geometry/Pastemask Bottom")
		(5 "F.SilkS" user "Ref Des/Silkscreen Top")
		(7 "B.SilkS" user "Ref Des/Silkscreen Bottom")
		(1 "F.Mask" user "Board Geometry/Soldermask Top")
		(3 "B.Mask" user "Board Geometry/Soldermask Bottom")
		(17 "Dwgs.User" user "User.Drawings")
		(19 "Cmts.User" user "User.Comments")
		(21 "Eco1.User" user "User.Eco1")
		(23 "Eco2.User" user "User.Eco2")
		(25 "Edge.Cuts" user "Board Geometry/Outline")
		(27 "Margin" user)
		(31 "F.CrtYd" user "Package Geometry/Place Bound Top")
		(29 "B.CrtYd" user "Package Geometry/Place Bound Bottom")
		(35 "F.Fab" user "Ref Des/Assembly Top")
		(33 "B.Fab" user "Ref Des/Assembly Bottom")
	)
	(footprint ""
		(layer "F.Cu")
		(at 429.657764 -27.006296 -90)
		(property "Reference" "PR7128"
			(at 0 0 270)
			(layer "F.SilkS")
			(hide yes)
			(effects
				(font
					(size 1.27 1.27)
				)
			)
		)
		(property "Value" ""
			(at 0 0 270)
			(layer "F.Fab")
			(effects
				(font
					(size 1.27 1.27)
				)
			)
		)
		(duplicate_pad_numbers_are_jumpers no)
		(fp_line
			(start -0.7874 0.4064)
			(end -0.7874 -0.4064)
			(stroke
				(width 0.1524)
				(type default)
			)
			(layer "F.SilkS")
		)
		(fp_line
			(start 0.7874 0.4064)
			(end -0.7874 0.4064)
			(stroke
				(width 0.1524)
				(type default)
			)
			(layer "F.SilkS")
		)
		(fp_line
			(start -0.7874 -0.4064)
			(end 0.7874 -0.4064)
			(stroke
				(width 0.1524)
				(type default)
			)
			(layer "F.SilkS")
		)
		(fp_line
			(start 0.7874 -0.4064)
			(end 0.7874 0.4064)
			(stroke
				(width 0.1524)
				(type default)
			)
			(layer "F.SilkS")
		)
		(fp_line
			(start -0.67945 0.3048)
			(end -0.67945 -0.305054)
			(stroke
				(width 0.1)
				(type default)
			)
			(layer "F.Fab")
		)
		(fp_line
			(start -0.12065 0.3048)
			(end -0.67945 0.3048)
			(stroke
				(width 0.1)
				(type default)
			)
			(layer "F.Fab")
		)
		(fp_line
			(start 0.120396 0.3048)
			(end 0.120396 0.2794)
			(stroke
				(width 0.1)
				(type default)
			)
			(layer "F.Fab")
		)
		(fp_line
			(start 0.67945 0.3048)
			(end 0.120396 0.3048)
			(stroke
				(width 0.1)
				(type default)
			)
			(layer "F.Fab")
		)
		(fp_line
			(start -0.12065 0.2794)
			(end -0.12065 0.3048)
			(stroke
				(width 0.1)
				(type default)
			)
			(layer "F.Fab")
		)
		(fp_line
			(start 0.120396 0.2794)
			(end -0.12065 0.2794)
			(stroke
				(width 0.1)
				(type default)
			)
			(layer "F.Fab")
		)
		(fp_line
			(start -0.12065 -0.2794)
			(end 0.12065 -0.2794)
			(stroke
				(width 0.1)
				(type default)
			)
			(layer "F.Fab")
		)
		(fp_line
			(start 0.12065 -0.2794)
			(end 0.12065 -0.3048)
			(stroke
				(width 0.1)
				(type default)
			)
			(layer "F.Fab")
		)
		(fp_line
			(start 0.12065 -0.3048)
			(end 0.67945 -0.3048)
			(stroke
				(width 0.1)
				(type default)
			)
			(layer "F.Fab")
		)
		(fp_line
			(start 0.67945 -0.3048)
			(end 0.67945 0.3048)
			(stroke
				(width 0.1)
				(type default)
			)
			(layer "F.Fab")
		)
		(fp_line
			(start -0.67945 -0.305054)
			(end -0.12065 -0.305054)
			(stroke
				(width 0.1)
				(type default)
			)
			(layer "F.Fab")
		)
		(fp_line
			(start -0.12065 -0.305054)
			(end -0.12065 -0.2794)
			(stroke
				(width 0.1)
				(type default)
			)
			(layer "F.Fab")
		)
		(pad "1" smd circle
			(at -0.40005 0 270)
			(size 0 0)
			(layers "F.Cu" "F.Mask" "F.Paste")
			(net "P3V3_SSD15_CO_MODE")
		)
		(pad "2" smd circle
			(at 0.40005 0 270)
			(size 0 0)
			(layers "F.Cu" "F.Mask" "F.Paste")
			(net "GND")
		)
	)
	(footprint ""
		(layer "F.Cu")
		(at 189.77356 -402.66874 -90)
		(property "Reference" "R4414"
			(at 0 0 270)
			(layer "F.SilkS")
			(hide yes)
			(effects
				(font
					(size 1.27 1.27)
				)
			)
		)
		(property "Value" ""
			(at 0 0 270)
			(layer "F.Fab")
			(effects
				(font
					(size 1.27 1.27)
				)
			)
		)
		(duplicate_pad_numbers_are_jumpers no)
		(fp_line
			(start -0.7874 0.4064)
			(end -0.7874 -0.4064)
			(stroke
				(width 0.1524)
				(type default)
			)
			(layer "F.SilkS")
		)
		(fp_line
			(start 0.7874 0.4064)
			(end -0.7874 0.4064)
			(stroke
				(width 0.1524)
				(type default)
			)
			(layer "F.SilkS")
		)
		(fp_line
			(start -0.7874 -0.4064)
			(end 0.7874 -0.4064)
			(stroke
				(width 0.1524)
				(type default)
			)
			(layer "F.SilkS")
		)
		(fp_line
			(start 0.7874 -0.4064)
			(end 0.7874 0.4064)
			(stroke
				(width 0.1524)
				(type default)
			)
			(layer "F.SilkS")
		)
		(fp_line
			(start -0.67945 0.3048)
			(end -0.67945 -0.305054)
			(stroke
				(width 0.1)
				(type default)
			)
			(layer "F.Fab")
		)
		(fp_line
			(start -0.12065 0.3048)
			(end -0.67945 0.3048)
			(stroke
				(width 0.1)
				(type default)
			)
			(layer "F.Fab")
		)
		(fp_line
			(start 0.120396 0.3048)
			(end 0.120396 0.2794)
			(stroke
				(width 0.1)
				(type default)
			)
			(layer "F.Fab")
		)
		(fp_line
			(start 0.67945 0.3048)
			(end 0.120396 0.3048)
			(stroke
				(width 0.1)
				(type default)
			)
			(layer "F.Fab")
		)
		(fp_line
			(start -0.12065 0.2794)
			(end -0.12065 0.3048)
			(stroke
				(width 0.1)
				(type default)
			)
			(layer "F.Fab")
		)
		(fp_line
			(start 0.120396 0.2794)
			(end -0.12065 0.2794)
			(stroke
				(width 0.1)
				(type default)
			)
			(layer "F.Fab")
		)
		(fp_line
			(start -0.12065 -0.2794)
			(end 0.12065 -0.2794)
			(stroke
				(width 0.1)
				(type default)
			)
			(layer "F.Fab")
		)
		(fp_line
			(start 0.12065 -0.2794)
			(end 0.12065 -0.3048)
			(stroke
				(width 0.1)
				(type default)
			)
			(layer "F.Fab")
		)
		(fp_line
			(start 0.12065 -0.3048)
			(end 0.67945 -0.3048)
			(stroke
				(width 0.1)
				(type default)
			)
			(layer "F.Fab")
		)
		(fp_line
			(start 0.67945 -0.3048)
			(end 0.67945 0.3048)
			(stroke
				(width 0.1)
				(type default)
			)
			(layer "F.Fab")
		)
		(fp_line
			(start -0.67945 -0.305054)
			(end -0.12065 -0.305054)
			(stroke
				(width 0.1)
				(type default)
			)
			(layer "F.Fab")
		)
		(fp_line
			(start -0.12065 -0.305054)
			(end -0.12065 -0.2794)
			(stroke
				(width 0.1)
				(type default)
			)
			(layer "F.Fab")
		)
		(pad "1" smd circle
			(at -0.40005 0 270)
			(size 0 0)
			(layers "F.Cu" "F.Mask" "F.Paste")
			(net "A_P12V_AUX_ADR_TRIGGER")
		)
		(pad "2" smd circle
			(at 0.40005 0 270)
			(size 0 0)
			(layers "F.Cu" "F.Mask" "F.Paste")
			(net "P12V_AUX")
		)
	)
	(footprint ""
		(layer "F.Cu")
		(at 269.448026 -102.009702)
		(property "Reference" "C484"
			(at 0 0 0)
			(layer "F.SilkS")
			(hide yes)
			(effects
				(font
					(size 1.27 1.27)
				)
			)
		)
		(property "Value" ""
			(at 0 0 0)
			(layer "F.Fab")
			(effects
				(font
					(size 1.27 1.27)
				)
			)
		)
		(duplicate_pad_numbers_are_jumpers no)
		(fp_line
			(start -0.299974 -0.150114)
			(end 0.299974 -0.150114)
			(stroke
				(width 0.1)
				(type default)
			)
			(layer "F.Fab")
		)
		(fp_line
			(start -0.299974 0.150114)
			(end -0.299974 -0.150114)
			(stroke
				(width 0.1)
				(type default)
			)
			(layer "F.Fab")
		)
		(fp_line
			(start 0.299974 -0.150114)
			(end 0.299974 0.150114)
			(stroke
				(width 0.1)
				(type default)
			)
			(layer "F.Fab")
		)
		(fp_line
			(start 0.299974 0.150114)
			(end -0.299974 0.150114)
			(stroke
				(width 0.1)
				(type default)
			)
			(layer "F.Fab")
		)
		(pad "1" smd rect
			(at -0.2667 0)
			(size 0.3048 0.381)
			(layers "F.Cu" "F.Mask" "F.Paste")
			(net "P5E_PEX2_STN1_TX_DP<17>")
		)
		(pad "2" smd rect
			(at 0.2667 0)
			(size 0.3048 0.381)
			(layers "F.Cu" "F.Mask" "F.Paste")
			(net "P5E_PEX2_STN1_TX_C_DP<17>")
		)
	)
	(footprint ""
		(layer "F.Cu")
		(at 142.368016 -56.353456)
		(property "Reference" "C2862"
			(at 0 0 0)
			(layer "F.SilkS")
			(hide yes)
			(effects
				(font
					(size 1.27 1.27)
				)
			)
		)
		(property "Value" ""
			(at 0 0 0)
			(layer "F.Fab")
			(effects
				(font
					(size 1.27 1.27)
				)
			)
		)
		(duplicate_pad_numbers_are_jumpers no)
		(fp_line
			(start -0.7874 -0.4064)
			(end 0.7874 -0.4064)
			(stroke
				(width 0.1524)
				(type default)
			)
			(layer "F.SilkS")
		)
		(fp_line
			(start -0.7874 0.4064)
			(end -0.7874 -0.4064)
			(stroke
				(width 0.1524)
				(type default)
			)
			(layer "F.SilkS")
		)
		(fp_line
			(start 0.7874 -0.4064)
			(end 0.7874 0.4064)
			(stroke
				(width 0.1524)
				(type default)
			)
			(layer "F.SilkS")
		)
		(fp_line
			(start 0.7874 0.4064)
			(end -0.7874 0.4064)
			(stroke
				(width 0.1524)
				(type default)
			)
			(layer "F.SilkS")
		)
		(fp_line
			(start -0.67945 -0.305054)
			(end -0.12065 -0.305054)
			(stroke
				(width 0.1)
				(type default)
			)
			(layer "F.Fab")
		)
		(fp_line
			(start -0.67945 0.3048)
			(end -0.67945 -0.305054)
			(stroke
				(width 0.1)
				(type default)
			)
			(layer "F.Fab")
		)
		(fp_line
			(start -0.12065 -0.305054)
			(end -0.12065 -0.2794)
			(stroke
				(width 0.1)
				(type default)
			)
			(layer "F.Fab")
		)
		(fp_line
			(start -0.12065 -0.2794)
			(end 0.12065 -0.2794)
			(stroke
				(width 0.1)
				(type default)
			)
			(layer "F.Fab")
		)
		(fp_line
			(start -0.12065 0.2794)
			(end -0.12065 0.3048)
			(stroke
				(width 0.1)
				(type default)
			)
			(layer "F.Fab")
		)
		(fp_line
			(start -0.12065 0.3048)
			(end -0.67945 0.3048)
			(stroke
				(width 0.1)
				(type default)
			)
			(layer "F.Fab")
		)
		(fp_line
			(start 0.120396 0.2794)
			(end -0.12065 0.2794)
			(stroke
				(width 0.1)
				(type default)
			)
			(layer "F.Fab")
		)
		(fp_line
			(start 0.120396 0.3048)
			(end 0.120396 0.2794)
			(stroke
				(width 0.1)
				(type default)
			)
			(layer "F.Fab")
		)
		(fp_line
			(start 0.12065 -0.3048)
			(end 0.67945 -0.3048)
			(stroke
				(width 0.1)
				(type default)
			)
			(layer "F.Fab")
		)
		(fp_line
			(start 0.12065 -0.2794)
			(end 0.12065 -0.3048)
			(stroke
				(width 0.1)
				(type default)
			)
			(layer "F.Fab")
		)
		(fp_line
			(start 0.67945 -0.3048)
			(end 0.67945 0.3048)
			(stroke
				(width 0.1)
				(type default)
			)
			(layer "F.Fab")
		)
		(fp_line
			(start 0.67945 0.3048)
			(end 0.120396 0.3048)
			(stroke
				(width 0.1)
				(type default)
			)
			(layer "F.Fab")
		)
		(pad "1" smd circle
			(at -0.40005 0)
			(size 0 0)
			(layers "F.Cu" "F.Mask" "F.Paste")
			(net "SSD4_PWR_EN_R")
		)
		(pad "2" smd circle
			(at 0.40005 0)
			(size 0 0)
			(layers "F.Cu" "F.Mask" "F.Paste")
			(net "GND")
		)
	)
	(footprint ""
		(layer "F.Cu")
		(at 130.702304 -200.101962 90)
		(property "Reference" "C4494"
			(at 0 0 90)
			(layer "F.SilkS")
			(hide yes)
			(effects
				(font
					(size 1.27 1.27)
				)
			)
		)
		(property "Value" ""
			(at 0 0 90)
			(layer "F.Fab")
			(effects
				(font
					(size 1.27 1.27)
				)
			)
		)
		(duplicate_pad_numbers_are_jumpers no)
		(fp_line
			(start 0.7874 -0.4064)
			(end 0.7874 0.4064)
			(stroke
				(width 0.1524)
				(type default)
			)
			(layer "F.SilkS")
		)
		(fp_line
			(start -0.7874 -0.4064)
			(end 0.7874 -0.4064)
			(stroke
				(width 0.1524)
				(type default)
			)
			(layer "F.SilkS")
		)
		(fp_line
			(start 0.7874 0.4064)
			(end -0.7874 0.4064)
			(stroke
				(width 0.1524)
				(type default)
			)
			(layer "F.SilkS")
		)
		(fp_line
			(start -0.7874 0.4064)
			(end -0.7874 -0.4064)
			(stroke
				(width 0.1524)
				(type default)
			)
			(layer "F.SilkS")
		)
		(fp_line
			(start -0.12065 -0.305054)
			(end -0.12065 -0.2794)
			(stroke
				(width 0.1)
				(type default)
			)
			(layer "F.Fab")
		)
		(fp_line
			(start -0.67945 -0.305054)
			(end -0.12065 -0.305054)
			(stroke
				(width 0.1)
				(type default)
			)
			(layer "F.Fab")
		)
		(fp_line
			(start 0.67945 -0.3048)
			(end 0.67945 0.3048)
			(stroke
				(width 0.1)
				(type default)
			)
			(layer "F.Fab")
		)
		(fp_line
			(start 0.12065 -0.3048)
			(end 0.67945 -0.3048)
			(stroke
				(width 0.1)
				(type default)
			)
			(layer "F.Fab")
		)
		(fp_line
			(start 0.12065 -0.2794)
			(end 0.12065 -0.3048)
			(stroke
				(width 0.1)
				(type default)
			)
			(layer "F.Fab")
		)
		(fp_line
			(start -0.12065 -0.2794)
			(end 0.12065 -0.2794)
			(stroke
				(width 0.1)
				(type default)
			)
			(layer "F.Fab")
		)
		(fp_line
			(start 0.120396 0.2794)
			(end -0.12065 0.2794)
			(stroke
				(width 0.1)
				(type default)
			)
			(layer "F.Fab")
		)
		(fp_line
			(start -0.12065 0.2794)
			(end -0.12065 0.3048)
			(stroke
				(width 0.1)
				(type default)
			)
			(layer "F.Fab")
		)
		(fp_line
			(start 0.67945 0.3048)
			(end 0.120396 0.3048)
			(stroke
				(width 0.1)
				(type default)
			)
			(layer "F.Fab")
		)
		(fp_line
			(start 0.120396 0.3048)
			(end 0.120396 0.2794)
			(stroke
				(width 0.1)
				(type default)
			)
			(layer "F.Fab")
		)
		(fp_line
			(start -0.12065 0.3048)
			(end -0.67945 0.3048)
			(stroke
				(width 0.1)
				(type default)
			)
			(layer "F.Fab")
		)
		(fp_line
			(start -0.67945 0.3048)
			(end -0.67945 -0.305054)
			(stroke
				(width 0.1)
				(type default)
			)
			(layer "F.Fab")
		)
		(pad "1" smd circle
			(at -0.40005 0 90)
			(size 0 0)
			(layers "F.Cu" "F.Mask" "F.Paste")
			(net "NIC7_CLK_EN_R_N")
		)
		(pad "2" smd circle
			(at 0.40005 0 90)
			(size 0 0)
			(layers "F.Cu" "F.Mask" "F.Paste")
			(net "GND")
		)
	)
	(footprint ""
		(layer "F.Cu")
		(at 270.766286 -250.070874 -90)
		(property "Reference" "R1335"
			(at 0 0 270)
			(layer "F.SilkS")
			(hide yes)
			(effects
				(font
					(size 1.27 1.27)
				)
			)
		)
		(property "Value" ""
			(at 0 0 270)
			(layer "F.Fab")
			(effects
				(font
					(size 1.27 1.27)
				)
			)
		)
		(duplicate_pad_numbers_are_jumpers no)
		(fp_line
			(start -0.7874 0.4064)
			(end -0.7874 -0.4064)
			(stroke
				(width 0.1524)
				(type default)
			)
			(layer "F.SilkS")
		)
		(fp_line
			(start 0.7874 0.4064)
			(end -0.7874 0.4064)
			(stroke
				(width 0.1524)
				(type default)
			)
			(layer "F.SilkS")
		)
		(fp_line
			(start -0.7874 -0.4064)
			(end 0.7874 -0.4064)
			(stroke
				(width 0.1524)
				(type default)
			)
			(layer "F.SilkS")
		)
		(fp_line
			(start 0.7874 -0.4064)
			(end 0.7874 0.4064)
			(stroke
				(width 0.1524)
				(type default)
			)
			(layer "F.SilkS")
		)
		(fp_line
			(start -0.67945 0.3048)
			(end -0.67945 -0.305054)
			(stroke
				(width 0.1)
				(type default)
			)
			(layer "F.Fab")
		)
		(fp_line
			(start -0.12065 0.3048)
			(end -0.67945 0.3048)
			(stroke
				(width 0.1)
				(type default)
			)
			(layer "F.Fab")
		)
		(fp_line
			(start 0.120396 0.3048)
			(end 0.120396 0.2794)
			(stroke
				(width 0.1)
				(type default)
			)
			(layer "F.Fab")
		)
		(fp_line
			(start 0.67945 0.3048)
			(end 0.120396 0.3048)
			(stroke
				(width 0.1)
				(type default)
			)
			(layer "F.Fab")
		)
		(fp_line
			(start -0.12065 0.2794)
			(end -0.12065 0.3048)
			(stroke
				(width 0.1)
				(type default)
			)
			(layer "F.Fab")
		)
		(fp_line
			(start 0.120396 0.2794)
			(end -0.12065 0.2794)
			(stroke
				(width 0.1)
				(type default)
			)
			(layer "F.Fab")
		)
		(fp_line
			(start -0.12065 -0.2794)
			(end 0.12065 -0.2794)
			(stroke
				(width 0.1)
				(type default)
			)
			(layer "F.Fab")
		)
		(fp_line
			(start 0.12065 -0.2794)
			(end 0.12065 -0.3048)
			(stroke
				(width 0.1)
				(type default)
			)
			(layer "F.Fab")
		)
		(fp_line
			(start 0.12065 -0.3048)
			(end 0.67945 -0.3048)
			(stroke
				(width 0.1)
				(type default)
			)
			(layer "F.Fab")
		)
		(fp_line
			(start 0.67945 -0.3048)
			(end 0.67945 0.3048)
			(stroke
				(width 0.1)
				(type default)
			)
			(layer "F.Fab")
		)
		(fp_line
			(start -0.67945 -0.305054)
			(end -0.12065 -0.305054)
			(stroke
				(width 0.1)
				(type default)
			)
			(layer "F.Fab")
		)
		(fp_line
			(start -0.12065 -0.305054)
			(end -0.12065 -0.2794)
			(stroke
				(width 0.1)
				(type default)
			)
			(layer "F.Fab")
		)
		(pad "1" smd circle
			(at -0.40005 0 270)
			(size 0 0)
			(layers "F.Cu" "F.Mask" "F.Paste")
			(net "PEX2_DBG_MODE4")
		)
		(pad "2" smd circle
			(at 0.40005 0 270)
			(size 0 0)
			(layers "F.Cu" "F.Mask" "F.Paste")
			(net "P1V8_PEX")
		)
	)
	(footprint ""
		(layer "F.Cu")
		(at 379.633988 -6.868922)
		(property "Reference" "R5822"
			(at 0 0 0)
			(layer "F.SilkS")
			(hide yes)
			(effects
				(font
					(size 1.27 1.27)
				)
			)
		)
		(property "Value" ""
			(at 0 0 0)
			(layer "F.Fab")
			(effects
				(font
					(size 1.27 1.27)
				)
			)
		)
		(duplicate_pad_numbers_are_jumpers no)
		(fp_line
			(start -0.7874 -0.4064)
			(end 0.7874 -0.4064)
			(stroke
				(width 0.1524)
				(type default)
			)
			(layer "F.SilkS")
		)
		(fp_line
			(start -0.7874 0.4064)
			(end -0.7874 -0.4064)
			(stroke
				(width 0.1524)
				(type default)
			)
			(layer "F.SilkS")
		)
		(fp_line
			(start 0.7874 -0.4064)
			(end 0.7874 0.4064)
			(stroke
				(width 0.1524)
				(type default)
			)
			(layer "F.SilkS")
		)
		(fp_line
			(start 0.7874 0.4064)
			(end -0.7874 0.4064)
			(stroke
				(width 0.1524)
				(type default)
			)
			(layer "F.SilkS")
		)
		(fp_line
			(start -0.67945 -0.305054)
			(end -0.12065 -0.305054)
			(stroke
				(width 0.1)
				(type default)
			)
			(layer "F.Fab")
		)
		(fp_line
			(start -0.67945 0.3048)
			(end -0.67945 -0.305054)
			(stroke
				(width 0.1)
				(type default)
			)
			(layer "F.Fab")
		)
		(fp_line
			(start -0.12065 -0.305054)
			(end -0.12065 -0.2794)
			(stroke
				(width 0.1)
				(type default)
			)
			(layer "F.Fab")
		)
		(fp_line
			(start -0.12065 -0.2794)
			(end 0.12065 -0.2794)
			(stroke
				(width 0.1)
				(type default)
			)
			(layer "F.Fab")
		)
		(fp_line
			(start -0.12065 0.2794)
			(end -0.12065 0.3048)
			(stroke
				(width 0.1)
				(type default)
			)
			(layer "F.Fab")
		)
		(fp_line
			(start -0.12065 0.3048)
			(end -0.67945 0.3048)
			(stroke
				(width 0.1)
				(type default)
			)
			(layer "F.Fab")
		)
		(fp_line
			(start 0.120396 0.2794)
			(end -0.12065 0.2794)
			(stroke
				(width 0.1)
				(type default)
			)
			(layer "F.Fab")
		)
		(fp_line
			(start 0.120396 0.3048)
			(end 0.120396 0.2794)
			(stroke
				(width 0.1)
				(type default)
			)
			(layer "F.Fab")
		)
		(fp_line
			(start 0.12065 -0.3048)
			(end 0.67945 -0.3048)
			(stroke
				(width 0.1)
				(type default)
			)
			(layer "F.Fab")
		)
		(fp_line
			(start 0.12065 -0.2794)
			(end 0.12065 -0.3048)
			(stroke
				(width 0.1)
				(type default)
			)
			(layer "F.Fab")
		)
		(fp_line
			(start 0.67945 -0.3048)
			(end 0.67945 0.3048)
			(stroke
				(width 0.1)
				(type default)
			)
			(layer "F.Fab")
		)
		(fp_line
			(start 0.67945 0.3048)
			(end 0.120396 0.3048)
			(stroke
				(width 0.1)
				(type default)
			)
			(layer "F.Fab")
		)
		(pad "1" smd circle
			(at -0.40005 0)
			(size 0 0)
			(layers "F.Cu" "F.Mask" "F.Paste")
			(net "LM75_3_A1")
		)
		(pad "2" smd circle
			(at 0.40005 0)
			(size 0 0)
			(layers "F.Cu" "F.Mask" "F.Paste")
			(net "GND")
		)
	)
)
